# S9S_MB_2U (Grand Teton) — schematic parts with pin connectivity, parts 5880–5880 of 6093; source: Cadence DE-HDL packaged netlist (pstxprt.dat, pstxnet.dat, pstchip.dat)

U2  SOCKET4677_AZIF0045P001C01CS  SOCKET4677_AZIF0045-P001C01CS IO  pkg SOCKET4677_82X64-5XA_H466  page 13  (pins 3913-4238 of 4677)
  EP22  DDR4_SB_DQ23  BI  = M_E_CPU0_SB_DQ<23>
  EP24  DDR4_SB_DQS_DP7  BI  = M_E_CPU0_SB_DQS_DP<7>
  EP26  DDR4_SB_DQ18  BI  = M_E_CPU0_SB_DQ<18>
  EP28  DDR4_SB_DQ15  BI  = M_E_CPU0_SB_DQ<15>
  EP30  DDR4_SB_DQS_DP6  BI  = M_E_CPU0_SB_DQS_DP<6>
  EP32  DDR4_SB_DQ10  BI  = M_E_CPU0_SB_DQ<10>
  EP34  DDR4_SB_ECC3  BI  = M_E_CPU0_SB_CB<3>
  EP36  DDR4_SB_DQS_DP4  BI  = M_E_CPU0_SB_DQS_DP<4>
  EP38  DDR4_SB_ECC6  BI  = M_E_CPU0_SB_CB<6>
  EP40  DDR4_SB_CS_N0  OUT  = M_E_CPU0_SB_CS_N<0>
  EP42  DDR4_SB_PAR  OUT  = M_E_CPU0_SB_PAR
  EP44  DDR4_SB_CA3  OUT  = M_E_CPU0_SB_CA<3>
  EP47  DDR4_SA_CA5  OUT  = M_E_CPU0_SA_CA<5>
  EP49  DDR4_SA_CA0  OUT  = M_E_CPU0_SA_CA<0>
  EP51  DDR4_SA_CS_N0  OUT  = M_E_CPU0_SA_CS_N<0>
  EP53  DDR4_SA_ECC7  BI  = M_E_CPU0_SA_CB<7>
  EP55  DDR4_SA_DQS_DP9  BI  = M_E_CPU0_SA_DQS_DP<9>
  EP57  DDR4_SA_ECC2  BI  = M_E_CPU0_SA_CB<2>
  EP59  DDR4_SA_DQ31  BI  = M_E_CPU0_SA_DQ<31>
  EP61  DDR4_SA_DQS_DP8  BI  = M_E_CPU0_SA_DQS_DP<8>
  EP63  DDR4_SA_DQ26  BI  = M_E_CPU0_SA_DQ<26>
  EP65  DDR4_SA_DQ23  BI  = M_E_CPU0_SA_DQ<23>
  EP67  VSS1543  POWER  = GND
  EP69  VSS1452  POWER  = GND
  EP71  VSS1453  POWER  = GND
  EP73  DDR4_SA_DQ6  BI  = M_E_CPU0_SA_DQ<6>
  EP75  DDR4_SA_DQS_DN0  BI  = M_E_CPU0_SA_DQS_DN<0>
  EP77  VSS1454  POWER  = GND
  EP79  DDR4_SA_DQ2  BI  = M_E_CPU0_SA_DQ<2>
  EP81  UPI3_RX_DN1  IN  = GND
  EP83  VSS1545  POWER  = GND
  EP85  UPI3_TX_DN2  OUT  = NC
  EP87  UPI3_TX_DP3  OUT  = NC
  ER5  VSS1549  POWER  = GND
  ER7  VSS1550  POWER  = GND
  ER9  VSS1476  POWER  = GND
  ER11  DDR5_SB_DQ22  BI  = M_F_CPU0_SB_DQ<22>
  ER13  DDR5_SB_DQ19  BI  = M_F_CPU0_SB_DQ<19>
  ER15  VSS1456  POWER  = GND
  ER17  DDR4_SB_DQ30  BI  = M_E_CPU0_SB_DQ<30>
  ER19  DDR4_SB_DQ27  BI  = M_E_CPU0_SB_DQ<27>
  ER21  VSS1457  POWER  = GND
  ER23  DDR4_SB_DQ22  BI  = M_E_CPU0_SB_DQ<22>
  ER25  DDR4_SB_DQ19  BI  = M_E_CPU0_SB_DQ<19>
  ER27  VSS1547  POWER  = GND
  ER29  DDR4_SB_DQ14  BI  = M_E_CPU0_SB_DQ<14>
  ER31  DDR4_SB_DQ11  BI  = M_E_CPU0_SB_DQ<11>
  ER33  VSS1548  POWER  = GND
  ER35  DDR4_SB_ECC2  BI  = M_E_CPU0_SB_CB<2>
  ER37  DDR4_SB_ECC7  BI  = M_E_CPU0_SB_CB<7>
  ER39  VSS1462  POWER  = GND
  ER41  VSS1834  POWER  = GND
  ER43  VSS1835  POWER  = GND
  ER48  VSS1836  POWER  = GND
  ER50  VSS1837  POWER  = GND
  ER52  VSS1464  POWER  = GND
  ER54  DDR4_SA_ECC6  BI  = M_E_CPU0_SA_CB<6>
  ER56  DDR4_SA_ECC3  BI  = M_E_CPU0_SA_CB<3>
  ER58  VSS1467  POWER  = GND
  ER60  DDR4_SA_DQ30  BI  = M_E_CPU0_SA_DQ<30>
  ER62  DDR4_SA_DQ27  BI  = M_E_CPU0_SA_DQ<27>
  ER64  VSS1468  POWER  = GND
  ER66  DDR4_SA_DQ20  BI  = M_E_CPU0_SA_DQ<20>
  ER68  DDR4_SA_DQ19  BI  = M_E_CPU0_SA_DQ<19>
  ER70  VSS1551  POWER  = GND
  ER72  DDR4_SA_DQ7  BI  = M_E_CPU0_SA_DQ<7>
  ER74  VSS1552  POWER  = GND
  ER76  DDR4_SA_DQ3  BI  = M_E_CPU0_SA_DQ<3>
  ER78  VSS1553  POWER  = GND
  ER80  VSS1554  POWER  = GND
  ER82  UPI3_RX_DP1  IN  = GND
  ER84  VSS1555  POWER  = GND
  ER86  VSS1556  POWER  = GND
  ET8  DDR6_SB_DQ27  BI  = M_G_CPU0_SB_DQ<27>
  ET10  VSS1557  POWER  = GND
  ET12  DDR5_SB_DQS_DN7  BI  = M_F_CPU0_SB_DQS_DN<7>
  ET14  VSS1478  POWER  = GND
  ET16  VSS1559  POWER  = GND
  ET18  DDR4_SB_DQS_DN8  BI  = M_E_CPU0_SB_DQS_DN<8>
  ET20  VSS1480  POWER  = GND
  ET22  VSS1561  POWER  = GND
  ET24  DDR4_SB_DQS_DN7  BI  = M_E_CPU0_SB_DQS_DN<7>
  ET26  VSS1482  POWER  = GND
  ET28  VSS1562  POWER  = GND
  ET30  DDR4_SB_DQS_DN6  BI  = M_E_CPU0_SB_DQS_DN<6>
  ET32  VSS1484  POWER  = GND
  ET34  VSS1563  POWER  = GND
  ET36  DDR4_SB_DQS_DN4  BI  = M_E_CPU0_SB_DQS_DN<4>
  ET38  VSS1565  POWER  = GND
  ET40  DDR4_SB_CS_N1  OUT  = M_E_CPU0_SB_CS_N<1>
  ET42  DDR4_SB_CA5  OUT  = M_E_CPU0_SB_CA<5>
  ET49  DDR4_SA_CA1  OUT  = M_E_CPU0_SA_CA<1>
  ET51  DDR4_SA_CS_N1  OUT  = M_E_CPU0_SA_CS_N<1>
  ET53  VSS1491  POWER  = GND
  ET55  DDR4_SA_DQS_DN9  BI  = M_E_CPU0_SA_DQS_DN<9>
  ET57  VSS1569  POWER  = GND
  ET59  VSS1493  POWER  = GND
  ET61  DDR4_SA_DQS_DN8  BI  = M_E_CPU0_SA_DQS_DN<8>
  F4  VSS1573  POWER  = GND
  F6  VSS1507  POWER  = GND
  F8  DDR0_SB_DQ30  BI  = M_A_CPU0_SB_DQ<30>
  F10  DDR0_SB_DQ27  BI  = M_A_CPU0_SB_DQ<27>
  F12  VSS1494  POWER  = GND
  F14  DDR1_SB_DQ31  BI  = M_B_CPU0_SB_DQ<31>
  F16  DDR1_SB_DQ27  BI  = M_B_CPU0_SB_DQ<27>
  F18  VSS1495  POWER  = GND
  F20  DDR0_SB_DQ22  BI  = M_A_CPU0_SB_DQ<22>
  F22  DDR0_SB_DQ19  BI  = M_A_CPU0_SB_DQ<19>
  F24  VSS1570  POWER  = GND
  F26  DDR0_SB_DQ14  BI  = M_A_CPU0_SB_DQ<14>
  F28  DDR0_SB_DQ11  BI  = M_A_CPU0_SB_DQ<11>
  F30  VSS1571  POWER  = GND
  F32  DDR0_SB_ECC2  BI  = M_A_CPU0_SB_CB<2>
  F34  DDR0_SB_ECC7  BI  = M_A_CPU0_SB_CB<7>
  F36  VSS1572  POWER  = GND
  F38  DDR0_SB_CS_N2  OUT  = M_A_CPU0_SB_CS_N<2>
  F40  DDR0_SB_CA5  OUT  = M_A_CPU0_SB_CA<5>
  F42  VSS1502  POWER  = GND
  F44  DDR0_SB_CA1  OUT  = M_A_CPU0_SB_CA<1>
  F47  DDR23_DRAM_PWR_OK  IN  = PWRGD_DRAMPWRGD_CPU0_CD_LVC1_R
  F49  VSS1574  POWER  = GND
  F51  DDR0_SA_CA3  OUT  = M_A_CPU0_SA_CA<3>
  F53  DDR0_SA_CS_N3  OUT  = M_A_CPU0_SA_CS_N<3>
  F55  VSS1504  POWER  = GND
  F57  DDR0_SA_ECC6  BI  = M_A_CPU0_SA_CB<6>
  F59  DDR0_SA_ECC3  BI  = M_A_CPU0_SA_CB<3>
  F61  VSS1508  POWER  = GND
  F63  DDR0_SA_DQ30  BI  = M_A_CPU0_SA_DQ<30>
  F65  DDR0_SA_DQ27  BI  = M_A_CPU0_SA_DQ<27>
  F67  VSS1509  POWER  = GND
  F69  DDR0_SA_DQ22  BI  = M_A_CPU0_SA_DQ<22>
  F71  DDR0_SA_DQ19  BI  = M_A_CPU0_SA_DQ<19>
  F73  VSS1510  POWER  = GND
  F75  DDR0_SA_DQ7  BI  = M_A_CPU0_SA_DQ<7>
  F77  DDR0_SA_DQS_DP5  BI  = M_A_CPU0_SA_DQS_DP<5>
  F79  VSS1511  POWER  = GND
  F81  UPI2_RX_DN1  IN  = UPI_CPU1_CPU0_P2P2_DP<22>
  F83  VSS1576  POWER  = GND
  F85  UPI2_TX_DP1  OUT  = UPI_CPU0_CPU1_P2P2_DP<22>
  F87  UPI2_TX_DN3  OUT  = UPI_CPU0_CPU1_P2P2_DN<20>
  F89  VSS1577  POWER  = GND
  G3  VSS1521  POWER  = GND
  G5  RSVD161  BI  = NC_XTAL_CPU0_25M_IN
  G7  VSS1536  POWER  = GND
  G9  DDR0_SB_DQS_DN8  BI  = M_A_CPU0_SB_DQS_DN<8>
  G11  VSS1514  POWER  = GND
  G13  VSS1578  POWER  = GND
  G15  DDR1_SB_DQS_DP8  BI  = M_B_CPU0_SB_DQS_DP<8>
  G17  VSS1516  POWER  = GND
  G19  VSS1579  POWER  = GND
  G21  DDR0_SB_DQS_DN7  BI  = M_A_CPU0_SB_DQS_DN<7>
  G23  VSS1581  POWER  = GND
  G25  VSS1519  POWER  = GND
  G27  DDR0_SB_DQS_DN6  BI  = M_A_CPU0_SB_DQS_DN<6>
  G29  VSS1583  POWER  = GND
  G31  VSS1584  POWER  = GND
  G33  DDR0_SB_DQS_DN4  BI  = M_A_CPU0_SB_DQS_DN<4>
  G35  VSS1523  POWER  = GND
  G37  VSS1585  POWER  = GND
  G39  DDR0_SB_PAR  OUT  = M_A_CPU0_SB_PAR
  G41  VSS1586  POWER  = GND
  G43  VSS1588  POWER  = GND
  G45  DDR0_CLK_DN1  OUT  = M_A_CPU0_CLK_DN<1>
  G48  VSS1527  POWER  = GND
  G50  VSS1590  POWER  = GND
  G52  DDR0_SA_CA1  OUT  = M_A_CPU0_SA_CA<1>
  G54  VSS1591  POWER  = GND
  G56  VSS1592  POWER  = GND
  G58  DDR0_SA_DQS_DN9  BI  = M_A_CPU0_SA_DQS_DN<9>
  G60  VSS1532  POWER  = GND
  G62  VSS1593  POWER  = GND
  G64  DDR0_SA_DQS_DN8  BI  = M_A_CPU0_SA_DQS_DN<8>
  G66  VSS1534  POWER  = GND
  G68  VSS1535  POWER  = GND
  G70  DDR0_SA_DQS_DN7  BI  = M_A_CPU0_SA_DQS_DN<7>
  G72  VSS1594  POWER  = GND
  G74  VSS1538  POWER  = GND
  G76  DDR0_SA_DQ6  BI  = M_A_CPU0_SA_DQ<6>
  G78  DDR0_SA_DQ3  BI  = M_A_CPU0_SA_DQ<3>
  G80  UPI2_RX_DP0  IN  = UPI_CPU1_CPU0_P2P2_DP<23>
  G82  UPI2_RX_DN2  IN  = UPI_CPU1_CPU0_P2P2_DN<21>
  G84  VSS1600  POWER  = GND
  G86  UPI2_TX_DP4  OUT  = UPI_CPU0_CPU1_P2P2_DP<19>
  G88  VSS1601  POWER  = GND
  G90  VSS1604  POWER  = GND
  H2  VSS1546  POWER  = GND
  H4  VSS1615  POWER  = GND
  H6  VSS1621  POWER  = GND
  H8  VSS1626  POWER  = GND
  H10  VSS1605  POWER  = GND
  H12  RSVD162  BI  = TP_CPU0_A0_DEBUG_EN
  H14  VSS1544  POWER  = GND
  H16  VSS1606  POWER  = GND
  H18  DDR1_SB_DQS_DN2  BI  = M_B_CPU0_SB_DQS_DN<2>
  H20  VSS1607  POWER  = GND
  H22  VSS1608  POWER  = GND
  H24  DDR1_SB_DQS_DN1  BI  = M_B_CPU0_SB_DQS_DN<1>
  H26  VSS1609  POWER  = GND
  H28  VSS1610  POWER  = GND
  H30  DDR0_SB_DQS_DN0  BI  = M_A_CPU0_SB_DQS_DN<0>
  H32  VSS1611  POWER  = GND
  H34  VSS1612  POWER  = GND
  H36  DDR1_SB_DQS_DP9  BI  = M_B_CPU0_SB_DQS_DP<9>
  H38  VSS1613  POWER  = GND
  H40  VSS1616  POWER  = GND
  H42  DDR1_SB_CA6  OUT  = M_B_CPU0_SB_CA<6>
  H44  VSS1617  POWER  = GND
  H47  VSS1618  POWER  = GND
  H49  DDR1_SA_CA0  OUT  = M_B_CPU0_SA_CA<0>
  H51  VSS1558  POWER  = GND
  H53  VSS1619  POWER  = GND
  H55  DDR1_SA_DQS_DN4  BI  = M_B_CPU0_SA_DQS_DN<4>
  H57  VSS1560  POWER  = GND
  H59  VSS1620  POWER  = GND
  H61  DDR1_SA_DQS_DN2  BI  = M_B_CPU0_SA_DQS_DN<2>
  H63  VSS1622  POWER  = GND
  H65  VSS1564  POWER  = GND
  H67  DDR0_SA_DQS_DN1  BI  = M_A_CPU0_SA_DQS_DN<1>
  H69  VSS1623  POWER  = GND
  H71  VSS1624  POWER  = GND
  H73  DDR1_SA_DQS_DN0  BI  = M_B_CPU0_SA_DQS_DN<0>
  H75  VSS1567  POWER  = GND
  H77  DDR0_SA_DQS_DN5  BI  = M_A_CPU0_SA_DQS_DN<5>
  H79  VSS1625  POWER  = GND
  H81  VSS1627  POWER  = GND
  H83  UPI2_RX_DP2  IN  = UPI_CPU1_CPU0_P2P2_DP<21>
  H85  UPI2_TX_DN4  OUT  = UPI_CPU0_CPU1_P2P2_DN<19>
  H87  UPI2_TX_DP3  OUT  = UPI_CPU0_CPU1_P2P2_DP<20>
  H89  VCCFA_EHV_FIVRA84  POWER  = PVCCFA_EHV_FIVRA_CPU0
  J3  UPI0_TX_DP0  OUT  = UPI_CPU0_CPU1_P0P1_DP<0>
  J5  VSS1582  POWER  = GND
  J7  VCCFA_EHV_FIVRA86  POWER  = PVCCFA_EHV_FIVRA_CPU0
  J9  VSS1596  POWER  = GND
  J11  VCCFA_EHV_FIVRA85  POWER  = PVCCFA_EHV_FIVRA_CPU0
  J13  RSVD163  BI  = TP_CPU0_PPD
  J15  VSS1628  POWER  = GND
  J17  DDR1_SB_DQ20  BI  = M_B_CPU0_SB_DQ<20>
  J19  DDR1_SB_DQ17  BI  = M_B_CPU0_SB_DQ<17>
  J21  VSS1575  POWER  = GND
  J23  DDR1_SB_DQ12  BI  = M_B_CPU0_SB_DQ<12>
  J25  DDR1_SB_DQ9  BI  = M_B_CPU0_SB_DQ<9>
  J27  VSS1629  POWER  = GND
  J29  DDR0_SB_DQ4  BI  = M_A_CPU0_SB_DQ<4>
  J31  DDR0_SB_DQ1  BI  = M_A_CPU0_SB_DQ<1>
  J33  VSS1630  POWER  = GND
  J35  DDR1_SB_ECC0  BI  = M_B_CPU0_SB_CB<0>
  J37  DDR1_SB_ECC5  BI  = M_B_CPU0_SB_CB<5>
  J39  VSS1580  POWER  = GND
  J41  DDR1_SB_CS_N0  OUT  = M_B_CPU0_SB_CS_N<0>
  J43  DDR1_SB_CA4  OUT  = M_B_CPU0_SB_CA<4>
  J45  VSS1631  POWER  = GND
  J48  DDR1_SA_CA2  OUT  = M_B_CPU0_SA_CA<2>
  J50  DDR1_SA_CS_N1  OUT  = M_B_CPU0_SA_CS_N<1>
  J52  VSS1632  POWER  = GND
  J54  DDR1_SA_ECC4  BI  = M_B_CPU0_SA_CB<4>
  J56  DDR1_SA_ECC1  BI  = M_B_CPU0_SA_CB<1>
  J58  VSS1633  POWER  = GND
  J60  DDR1_SA_DQ20  BI  = M_B_CPU0_SA_DQ<20>
  J62  DDR1_SA_DQ17  BI  = M_B_CPU0_SA_DQ<17>
  J64  VSS1587  POWER  = GND
  J66  DDR0_SA_DQ12  BI  = M_A_CPU0_SA_DQ<12>
  J68  DDR0_SA_DQ9  BI  = M_A_CPU0_SA_DQ<9>
  J70  VSS1589  POWER  = GND
  J72  DDR1_SA_DQ4  BI  = M_B_CPU0_SA_DQ<4>
  J74  DDR1_SA_DQ1  BI  = M_B_CPU0_SA_DQ<1>
  J76  VSS1635  POWER  = GND
  J78  VSS1636  POWER  = GND
  J80  VCCFA_EHV_FIVRA87  POWER  = PVCCFA_EHV_FIVRA_CPU0
  J82  UPI2_RX_DN4  IN  = UPI_CPU1_CPU0_P2P2_DN<19>
  J84  VSS1637  POWER  = GND
  J86  VSS1638  POWER  = GND
  J88  VSS1595  POWER  = GND
  J90  PE4_RX_DN0  IN  = P5E_CPU0_PE4_RX_DN<0>
  K2  VSS1599  POWER  = GND
  K4  UPI0_TX_DN0  OUT  = UPI_CPU0_CPU1_P0P1_DN<0>
  K6  UPI0_RX_DN0  IN  = UPI_CPU1_CPU0_P1P0_DN<0>
  K8  VSS1641  POWER  = GND
  K10  PE0_RX_DN0  IN  = P5E_CPU0_PE0_RX_DN<0>
  K12  VSS1597  POWER  = GND
  K14  VSS1598  POWER  = GND
  K16  DDR1_SB_DQ21  BI  = M_B_CPU0_SB_DQ<21>
  K18  DDR1_SB_DQS_DP2  BI  = M_B_CPU0_SB_DQS_DP<2>
  K20  DDR1_SB_DQ16  BI  = M_B_CPU0_SB_DQ<16>
  K22  DDR1_SB_DQ13  BI  = M_B_CPU0_SB_DQ<13>
  K24  DDR1_SB_DQS_DP1  BI  = M_B_CPU0_SB_DQS_DP<1>
  K26  DDR1_SB_DQ8  BI  = M_B_CPU0_SB_DQ<8>
  K28  DDR0_SB_DQ5  BI  = M_A_CPU0_SB_DQ<5>
  K30  DDR0_SB_DQS_DP0  BI  = M_A_CPU0_SB_DQS_DP<0>
  K32  DDR0_SB_DQ0  BI  = M_A_CPU0_SB_DQ<0>
  K34  DDR1_SB_ECC1  BI  = M_B_CPU0_SB_CB<1>
  K36  DDR1_SB_DQS_DN9  BI  = M_B_CPU0_SB_DQS_DN<9>
  K38  DDR1_SB_ECC4  BI  = M_B_CPU0_SB_CB<4>
  K40  DDR1_SB_CS_N1  OUT  = M_B_CPU0_SB_CS_N<1>
  K42  VSS1602  POWER  = GND
  K44  DDR1_SB_CA2  OUT  = M_B_CPU0_SB_CA<2>
  K47  DDR1_SA_CA4  OUT  = M_B_CPU0_SA_CA<4>
  K49  VSS1603  POWER  = GND
  K51  DDR1_SA_CS_N0  OUT  = M_B_CPU0_SA_CS_N<0>
  K53  DDR1_SA_ECC5  BI  = M_B_CPU0_SA_CB<5>
  K55  DDR1_SA_DQS_DP4  BI  = M_B_CPU0_SA_DQS_DP<4>
  K57  DDR1_SA_ECC0  BI  = M_B_CPU0_SA_CB<0>
  K59  DDR1_SA_DQ21  BI  = M_B_CPU0_SA_DQ<21>
  K61  DDR1_SA_DQS_DP2  BI  = M_B_CPU0_SA_DQS_DP<2>
  K63  DDR1_SA_DQ16  BI  = M_B_CPU0_SA_DQ<16>
  K65  DDR0_SA_DQ13  BI  = M_A_CPU0_SA_DQ<13>
  K67  DDR0_SA_DQS_DP1  BI  = M_A_CPU0_SA_DQS_DP<1>
  K69  DDR0_SA_DQ8  BI  = M_A_CPU0_SA_DQ<8>
  K71  DDR1_SA_DQ5  BI  = M_B_CPU0_SA_DQ<5>
  K73  DDR1_SA_DQS_DP0  BI  = M_B_CPU0_SA_DQS_DP<0>
  K75  DDR1_SA_DQ0  BI  = M_B_CPU0_SA_DQ<0>
  K77  VSS1639  POWER  = GND
  K79  UPI2_RX_DN3  IN  = UPI_CPU1_CPU0_P2P2_DN<20>
  K81  UPI2_RX_DP5  IN  = UPI_CPU1_CPU0_P2P2_DP<18>
  K83  VSS1642  POWER  = GND
  K85  VSS1643  POWER  = GND
  K87  VCCFA_EHV_FIVRA88  POWER  = PVCCFA_EHV_FIVRA_CPU0
  K89  PE4_RX_DP0  IN  = P5E_CPU0_PE4_RX_DP<0>
  L3  UPI0_TX_DP1  OUT  = UPI_CPU0_CPU1_P0P1_DP<1>
  L5  VSS1671  POWER  = GND
  L7  UPI0_RX_DP0  IN  = UPI_CPU1_CPU0_P1P0_DP<0>
  L9  VSS1647  POWER  = GND
  L11  PE0_RX_DP0  IN  = P5E_CPU0_PE0_RX_DP<0>
  L13  VSS1644  POWER  = GND
  L15  VSS1645  POWER  = GND
  L17  VSS1650  POWER  = GND
  L19  VSS1614  POWER  = GND
